(kicad_pcb
	(version 20260206)
	(generator "pcbnew")
	(generator_version "10.0")
	(general
		(thickness 1.6)
		(legacy_teardrops no)
	)
	(paper "A4")
	(title_block
		(title "04192023_DAF0TMB3IC0_F0TG_MB_C_brd_V02_OCP.brd")
		(comment 1 "Grand Teton / footprints 7258-7263 of 8354")
	)
	(layers
		(0 "F.Cu" signal "TOP")
		(4 "In1.Cu" signal "GND")
		(6 "In2.Cu" signal "IN1")
		(8 "In3.Cu" signal "GND1")
		(10 "In4.Cu" signal "IN2")
		(12 "In5.Cu" signal "GND2")
		(14 "In6.Cu" signal "IN3")
		(16 "In7.Cu" signal "GND3")
		(18 "In8.Cu" signal "VCC")
		(20 "In9.Cu" signal "VCC1")
		(22 "In10.Cu" signal "GND4")
		(24 "In11.Cu" signal "IN4")
		(26 "In12.Cu" signal "GND5")
		(28 "In13.Cu" signal "IN5")
		(30 "In14.Cu" signal "GND6")
		(32 "In15.Cu" signal "IN6")
		(34 "In16.Cu" signal "GND7")
		(2 "B.Cu" signal "BOTTOM")
		(9 "F.Adhes" user "F.Adhesive")
		(11 "B.Adhes" user "B.Adhesive")
		(13 "F.Paste" user "Package Geometry/Pastemask Top")
		(15 "B.Paste" user "Package Geometry/Pastemask Bottom")
		(5 "F.SilkS" user "Ref Des/Silkscreen Top")
		(7 "B.SilkS" user "Ref Des/Silkscreen Bottom")
		(1 "F.Mask" user "Board Geometry/Soldermask Top")
		(3 "B.Mask" user "Board Geometry/Soldermask Bottom")
		(17 "Dwgs.User" user "User.Drawings")
		(19 "Cmts.User" user "User.Comments")
		(21 "Eco1.User" user "User.Eco1")
		(23 "Eco2.User" user "User.Eco2")
		(25 "Edge.Cuts" user "Board Geometry/Outline")
		(27 "Margin" user)
		(31 "F.CrtYd" user "Package Geometry/Place Bound Top")
		(29 "B.CrtYd" user "Package Geometry/Place Bound Bottom")
		(35 "F.Fab" user "Ref Des/Assembly Top")
		(33 "B.Fab" user "Ref Des/Assembly Bottom")
	)
	(footprint ""
		(layer "B.Cu")
		(at 90.746834 -308.606952 90)
		(property "Reference" "PR237"
			(at 0 0 90)
			(layer "B.SilkS")
			(hide yes)
			(effects
				(font
					(size 1.27 1.27)
				)
				(justify mirror)
			)
		)
		(property "Value" ""
			(at 0 0 90)
			(layer "B.Fab")
			(effects
				(font
					(size 1.27 1.27)
				)
				(justify mirror)
			)
		)
		(duplicate_pad_numbers_are_jumpers no)
		(fp_line
			(start 0.7874 -0.4064)
			(end -0.7874 -0.4064)
			(stroke
				(width 0.1524)
				(type default)
			)
			(layer "B.SilkS")
		)
		(fp_line
			(start -0.7874 -0.4064)
			(end -0.7874 0.4064)
			(stroke
				(width 0.1524)
				(type default)
			)
			(layer "B.SilkS")
		)
		(fp_line
			(start 0.7874 0.4064)
			(end 0.7874 -0.4064)
			(stroke
				(width 0.1524)
				(type default)
			)
			(layer "B.SilkS")
		)
		(fp_line
			(start -0.7874 0.4064)
			(end 0.7874 0.4064)
			(stroke
				(width 0.1524)
				(type default)
			)
			(layer "B.SilkS")
		)
		(fp_line
			(start 0.67945 -0.305054)
			(end 0.12065 -0.305054)
			(stroke
				(width 0.1)
				(type default)
			)
			(layer "B.Fab")
		)
		(fp_line
			(start 0.12065 -0.305054)
			(end 0.12065 -0.2794)
			(stroke
				(width 0.1)
				(type default)
			)
			(layer "B.Fab")
		)
		(fp_line
			(start -0.12065 -0.3048)
			(end -0.67945 -0.3048)
			(stroke
				(width 0.1)
				(type default)
			)
			(layer "B.Fab")
		)
		(fp_line
			(start -0.67945 -0.3048)
			(end -0.67945 0.3048)
			(stroke
				(width 0.1)
				(type default)
			)
			(layer "B.Fab")
		)
		(fp_line
			(start 0.12065 -0.2794)
			(end -0.12065 -0.2794)
			(stroke
				(width 0.1)
				(type default)
			)
			(layer "B.Fab")
		)
		(fp_line
			(start -0.12065 -0.2794)
			(end -0.12065 -0.3048)
			(stroke
				(width 0.1)
				(type default)
			)
			(layer "B.Fab")
		)
		(fp_line
			(start 0.12065 0.2794)
			(end 0.12065 0.3048)
			(stroke
				(width 0.1)
				(type default)
			)
			(layer "B.Fab")
		)
		(fp_line
			(start -0.120396 0.2794)
			(end 0.12065 0.2794)
			(stroke
				(width 0.1)
				(type default)
			)
			(layer "B.Fab")
		)
		(fp_line
			(start 0.67945 0.3048)
			(end 0.67945 -0.305054)
			(stroke
				(width 0.1)
				(type default)
			)
			(layer "B.Fab")
		)
		(fp_line
			(start 0.12065 0.3048)
			(end 0.67945 0.3048)
			(stroke
				(width 0.1)
				(type default)
			)
			(layer "B.Fab")
		)
		(fp_line
			(start -0.120396 0.3048)
			(end -0.120396 0.2794)
			(stroke
				(width 0.1)
				(type default)
			)
			(layer "B.Fab")
		)
		(fp_line
			(start -0.67945 0.3048)
			(end -0.120396 0.3048)
			(stroke
				(width 0.1)
				(type default)
			)
			(layer "B.Fab")
		)
		(pad "1" smd circle
			(at 0.40005 0 270)
			(size 0 0)
			(layers "B.Cu" "B.Mask" "B.Paste")
			(net "SVID_PVDDCR_CPU1_P1_SVD_R")
		)
		(pad "2" smd circle
			(at -0.40005 0 270)
			(size 0 0)
			(layers "B.Cu" "B.Mask" "B.Paste")
			(net "SVID_PVDDCR_CPU1_P1_SVD")
		)
	)
	(footprint ""
		(layer "B.Cu")
		(at 52.191412 -390.560052 90)
		(property "Reference" "C255"
			(at 0 0 90)
			(layer "B.SilkS")
			(hide yes)
			(effects
				(font
					(size 1.27 1.27)
				)
				(justify mirror)
			)
		)
		(property "Value" ""
			(at 0 0 90)
			(layer "B.Fab")
			(effects
				(font
					(size 1.27 1.27)
				)
				(justify mirror)
			)
		)
		(duplicate_pad_numbers_are_jumpers no)
		(fp_line
			(start 0.7874 -0.4064)
			(end -0.7874 -0.4064)
			(stroke
				(width 0.1524)
				(type default)
			)
			(layer "B.SilkS")
		)
		(fp_line
			(start -0.7874 -0.4064)
			(end -0.7874 0.4064)
			(stroke
				(width 0.1524)
				(type default)
			)
			(layer "B.SilkS")
		)
		(fp_line
			(start 0.7874 0.4064)
			(end 0.7874 -0.4064)
			(stroke
				(width 0.1524)
				(type default)
			)
			(layer "B.SilkS")
		)
		(fp_line
			(start -0.7874 0.4064)
			(end 0.7874 0.4064)
			(stroke
				(width 0.1524)
				(type default)
			)
			(layer "B.SilkS")
		)
		(fp_line
			(start 0.67945 -0.305054)
			(end 0.12065 -0.305054)
			(stroke
				(width 0.1)
				(type default)
			)
			(layer "B.Fab")
		)
		(fp_line
			(start 0.12065 -0.305054)
			(end 0.12065 -0.2794)
			(stroke
				(width 0.1)
				(type default)
			)
			(layer "B.Fab")
		)
		(fp_line
			(start -0.12065 -0.3048)
			(end -0.67945 -0.3048)
			(stroke
				(width 0.1)
				(type default)
			)
			(layer "B.Fab")
		)
		(fp_line
			(start -0.67945 -0.3048)
			(end -0.67945 0.3048)
			(stroke
				(width 0.1)
				(type default)
			)
			(layer "B.Fab")
		)
		(fp_line
			(start 0.12065 -0.2794)
			(end -0.12065 -0.2794)
			(stroke
				(width 0.1)
				(type default)
			)
			(layer "B.Fab")
		)
		(fp_line
			(start -0.12065 -0.2794)
			(end -0.12065 -0.3048)
			(stroke
				(width 0.1)
				(type default)
			)
			(layer "B.Fab")
		)
		(fp_line
			(start 0.12065 0.2794)
			(end 0.12065 0.3048)
			(stroke
				(width 0.1)
				(type default)
			)
			(layer "B.Fab")
		)
		(fp_line
			(start -0.120396 0.2794)
			(end 0.12065 0.2794)
			(stroke
				(width 0.1)
				(type default)
			)
			(layer "B.Fab")
		)
		(fp_line
			(start 0.67945 0.3048)
			(end 0.67945 -0.305054)
			(stroke
				(width 0.1)
				(type default)
			)
			(layer "B.Fab")
		)
		(fp_line
			(start 0.12065 0.3048)
			(end 0.67945 0.3048)
			(stroke
				(width 0.1)
				(type default)
			)
			(layer "B.Fab")
		)
		(fp_line
			(start -0.120396 0.3048)
			(end -0.120396 0.2794)
			(stroke
				(width 0.1)
				(type default)
			)
			(layer "B.Fab")
		)
		(fp_line
			(start -0.67945 0.3048)
			(end -0.120396 0.3048)
			(stroke
				(width 0.1)
				(type default)
			)
			(layer "B.Fab")
		)
		(pad "1" smd circle
			(at 0.40005 0 270)
			(size 0 0)
			(layers "B.Cu" "B.Mask" "B.Paste")
			(net "P0V9_CPU1_RT0_2A")
		)
		(pad "2" smd circle
			(at -0.40005 0 270)
			(size 0 0)
			(layers "B.Cu" "B.Mask" "B.Paste")
			(net "GND")
		)
	)
	(footprint ""
		(layer "B.Cu")
		(at 91.792044 -337.694524 -90)
		(property "Reference" "PR273"
			(at 0 0 90)
			(layer "B.SilkS")
			(hide yes)
			(effects
				(font
					(size 1.27 1.27)
				)
				(justify mirror)
			)
		)
		(property "Value" ""
			(at 0 0 90)
			(layer "B.Fab")
			(effects
				(font
					(size 1.27 1.27)
				)
				(justify mirror)
			)
		)
		(duplicate_pad_numbers_are_jumpers no)
		(fp_line
			(start -0.7874 0.4064)
			(end 0.7874 0.4064)
			(stroke
				(width 0.1524)
				(type default)
			)
			(layer "B.SilkS")
		)
		(fp_line
			(start 0.7874 0.4064)
			(end 0.7874 -0.4064)
			(stroke
				(width 0.1524)
				(type default)
			)
			(layer "B.SilkS")
		)
		(fp_line
			(start -0.7874 -0.4064)
			(end -0.7874 0.4064)
			(stroke
				(width 0.1524)
				(type default)
			)
			(layer "B.SilkS")
		)
		(fp_line
			(start 0.7874 -0.4064)
			(end -0.7874 -0.4064)
			(stroke
				(width 0.1524)
				(type default)
			)
			(layer "B.SilkS")
		)
		(fp_line
			(start -0.67945 0.3048)
			(end -0.120396 0.3048)
			(stroke
				(width 0.1)
				(type default)
			)
			(layer "B.Fab")
		)
		(fp_line
			(start -0.120396 0.3048)
			(end -0.120396 0.2794)
			(stroke
				(width 0.1)
				(type default)
			)
			(layer "B.Fab")
		)
		(fp_line
			(start 0.12065 0.3048)
			(end 0.67945 0.3048)
			(stroke
				(width 0.1)
				(type default)
			)
			(layer "B.Fab")
		)
		(fp_line
			(start 0.67945 0.3048)
			(end 0.67945 -0.305054)
			(stroke
				(width 0.1)
				(type default)
			)
			(layer "B.Fab")
		)
		(fp_line
			(start -0.120396 0.2794)
			(end 0.12065 0.2794)
			(stroke
				(width 0.1)
				(type default)
			)
			(layer "B.Fab")
		)
		(fp_line
			(start 0.12065 0.2794)
			(end 0.12065 0.3048)
			(stroke
				(width 0.1)
				(type default)
			)
			(layer "B.Fab")
		)
		(fp_line
			(start -0.12065 -0.2794)
			(end -0.12065 -0.3048)
			(stroke
				(width 0.1)
				(type default)
			)
			(layer "B.Fab")
		)
		(fp_line
			(start 0.12065 -0.2794)
			(end -0.12065 -0.2794)
			(stroke
				(width 0.1)
				(type default)
			)
			(layer "B.Fab")
		)
		(fp_line
			(start -0.67945 -0.3048)
			(end -0.67945 0.3048)
			(stroke
				(width 0.1)
				(type default)
			)
			(layer "B.Fab")
		)
		(fp_line
			(start -0.12065 -0.3048)
			(end -0.67945 -0.3048)
			(stroke
				(width 0.1)
				(type default)
			)
			(layer "B.Fab")
		)
		(fp_line
			(start 0.12065 -0.305054)
			(end 0.12065 -0.2794)
			(stroke
				(width 0.1)
				(type default)
			)
			(layer "B.Fab")
		)
		(fp_line
			(start 0.67945 -0.305054)
			(end 0.12065 -0.305054)
			(stroke
				(width 0.1)
				(type default)
			)
			(layer "B.Fab")
		)
		(pad "1" smd circle
			(at 0.40005 0 90)
			(size 0 0)
			(layers "B.Cu" "B.Mask" "B.Paste")
			(net "PVDDCR_CPU1_P1_VOS5")
		)
		(pad "2" smd circle
			(at -0.40005 0 90)
			(size 0 0)
			(layers "B.Cu" "B.Mask" "B.Paste")
			(net "PVDDCR_CPU1_P1")
		)
	)
	(footprint ""
		(layer "B.Cu")
		(at 371.551454 -257.930142)
		(property "Reference" "C2530"
			(at 0 0 0)
			(layer "B.SilkS")
			(hide yes)
			(effects
				(font
					(size 1.27 1.27)
				)
				(justify mirror)
			)
		)
		(property "Value" ""
			(at 0 0 0)
			(layer "B.Fab")
			(effects
				(font
					(size 1.27 1.27)
				)
				(justify mirror)
			)
		)
		(duplicate_pad_numbers_are_jumpers no)
		(fp_line
			(start -0.7874 -0.4064)
			(end -0.7874 0.4064)
			(stroke
				(width 0.1524)
				(type default)
			)
			(layer "B.SilkS")
		)
		(fp_line
			(start -0.7874 0.4064)
			(end 0.7874 0.4064)
			(stroke
				(width 0.1524)
				(type default)
			)
			(layer "B.SilkS")
		)
		(fp_line
			(start 0.7874 -0.4064)
			(end -0.7874 -0.4064)
			(stroke
				(width 0.1524)
				(type default)
			)
			(layer "B.SilkS")
		)
		(fp_line
			(start 0.7874 0.4064)
			(end 0.7874 -0.4064)
			(stroke
				(width 0.1524)
				(type default)
			)
			(layer "B.SilkS")
		)
		(fp_line
			(start -0.67945 -0.3048)
			(end -0.67945 0.3048)
			(stroke
				(width 0.1)
				(type default)
			)
			(layer "B.Fab")
		)
		(fp_line
			(start -0.67945 0.3048)
			(end -0.120396 0.3048)
			(stroke
				(width 0.1)
				(type default)
			)
			(layer "B.Fab")
		)
		(fp_line
			(start -0.12065 -0.3048)
			(end -0.67945 -0.3048)
			(stroke
				(width 0.1)
				(type default)
			)
			(layer "B.Fab")
		)
		(fp_line
			(start -0.12065 -0.2794)
			(end -0.12065 -0.3048)
			(stroke
				(width 0.1)
				(type default)
			)
			(layer "B.Fab")
		)
		(fp_line
			(start -0.120396 0.2794)
			(end 0.12065 0.2794)
			(stroke
				(width 0.1)
				(type default)
			)
			(layer "B.Fab")
		)
		(fp_line
			(start -0.120396 0.3048)
			(end -0.120396 0.2794)
			(stroke
				(width 0.1)
				(type default)
			)
			(layer "B.Fab")
		)
		(fp_line
			(start 0.12065 -0.305054)
			(end 0.12065 -0.2794)
			(stroke
				(width 0.1)
				(type default)
			)
			(layer "B.Fab")
		)
		(fp_line
			(start 0.12065 -0.2794)
			(end -0.12065 -0.2794)
			(stroke
				(width 0.1)
				(type default)
			)
			(layer "B.Fab")
		)
		(fp_line
			(start 0.12065 0.2794)
			(end 0.12065 0.3048)
			(stroke
				(width 0.1)
				(type default)
			)
			(layer "B.Fab")
		)
		(fp_line
			(start 0.12065 0.3048)
			(end 0.67945 0.3048)
			(stroke
				(width 0.1)
				(type default)
			)
			(layer "B.Fab")
		)
		(fp_line
			(start 0.67945 -0.305054)
			(end 0.12065 -0.305054)
			(stroke
				(width 0.1)
				(type default)
			)
			(layer "B.Fab")
		)
		(fp_line
			(start 0.67945 0.3048)
			(end 0.67945 -0.305054)
			(stroke
				(width 0.1)
				(type default)
			)
			(layer "B.Fab")
		)
		(pad "1" smd circle
			(at 0.40005 0 180)
			(size 0 0)
			(layers "B.Cu" "B.Mask" "B.Paste")
			(net "PVDDCR_SOC_P0")
		)
		(pad "2" smd circle
			(at -0.40005 0 180)
			(size 0 0)
			(layers "B.Cu" "B.Mask" "B.Paste")
			(net "GND")
		)
	)
	(footprint ""
		(layer "B.Cu")
		(at 206.429356 -380.206504 180)
		(property "Reference" "PR2522"
			(at 0 0 0)
			(layer "B.SilkS")
			(hide yes)
			(effects
				(font
					(size 1.27 1.27)
				)
				(justify mirror)
			)
		)
		(property "Value" ""
			(at 0 0 0)
			(layer "B.Fab")
			(effects
				(font
					(size 1.27 1.27)
				)
				(justify mirror)
			)
		)
		(duplicate_pad_numbers_are_jumpers no)
		(fp_line
			(start 0.7874 0.4064)
			(end 0.7874 -0.4064)
			(stroke
				(width 0.1524)
				(type default)
			)
			(layer "B.SilkS")
		)
		(fp_line
			(start 0.7874 -0.4064)
			(end -0.7874 -0.4064)
			(stroke
				(width 0.1524)
				(type default)
			)
			(layer "B.SilkS")
		)
		(fp_line
			(start -0.7874 0.4064)
			(end 0.7874 0.4064)
			(stroke
				(width 0.1524)
				(type default)
			)
			(layer "B.SilkS")
		)
		(fp_line
			(start -0.7874 -0.4064)
			(end -0.7874 0.4064)
			(stroke
				(width 0.1524)
				(type default)
			)
			(layer "B.SilkS")
		)
		(fp_line
			(start 0.67945 0.3048)
			(end 0.67945 -0.305054)
			(stroke
				(width 0.1)
				(type default)
			)
			(layer "B.Fab")
		)
		(fp_line
			(start 0.67945 -0.305054)
			(end 0.12065 -0.305054)
			(stroke
				(width 0.1)
				(type default)
			)
			(layer "B.Fab")
		)
		(fp_line
			(start 0.12065 0.3048)
			(end 0.67945 0.3048)
			(stroke
				(width 0.1)
				(type default)
			)
			(layer "B.Fab")
		)
		(fp_line
			(start 0.12065 0.2794)
			(end 0.12065 0.3048)
			(stroke
				(width 0.1)
				(type default)
			)
			(layer "B.Fab")
		)
		(fp_line
			(start 0.12065 -0.2794)
			(end -0.12065 -0.2794)
			(stroke
				(width 0.1)
				(type default)
			)
			(layer "B.Fab")
		)
		(fp_line
			(start 0.12065 -0.305054)
			(end 0.12065 -0.2794)
			(stroke
				(width 0.1)
				(type default)
			)
			(layer "B.Fab")
		)
		(fp_line
			(start -0.120396 0.3048)
			(end -0.120396 0.2794)
			(stroke
				(width 0.1)
				(type default)
			)
			(layer "B.Fab")
		)
		(fp_line
			(start -0.120396 0.2794)
			(end 0.12065 0.2794)
			(stroke
				(width 0.1)
				(type default)
			)
			(layer "B.Fab")
		)
		(fp_line
			(start -0.12065 -0.2794)
			(end -0.12065 -0.3048)
			(stroke
				(width 0.1)
				(type default)
			)
			(layer "B.Fab")
		)
		(fp_line
			(start -0.12065 -0.3048)
			(end -0.67945 -0.3048)
			(stroke
				(width 0.1)
				(type default)
			)
			(layer "B.Fab")
		)
		(fp_line
			(start -0.67945 0.3048)
			(end -0.120396 0.3048)
			(stroke
				(width 0.1)
				(type default)
			)
			(layer "B.Fab")
		)
		(fp_line
			(start -0.67945 -0.3048)
			(end -0.67945 0.3048)
			(stroke
				(width 0.1)
				(type default)
			)
			(layer "B.Fab")
		)
		(pad "1" smd circle
			(at 0.40005 0)
			(size 0 0)
			(layers "B.Cu" "B.Mask" "B.Paste")
			(net "P12V_HSC_SENSE2_P")
		)
		(pad "2" smd circle
			(at -0.40005 0)
			(size 0 0)
			(layers "B.Cu" "B.Mask" "B.Paste")
			(net "P12V_HSC_SENSE2_R3_P")
		)
	)
	(footprint ""
		(layer "B.Cu")
		(at 397.935958 -313.477148)
		(property "Reference" "R5102"
			(at 0 0 0)
			(layer "B.SilkS")
			(hide yes)
			(effects
				(font
					(size 1.27 1.27)
				)
				(justify mirror)
			)
		)
		(property "Value" ""
			(at 0 0 0)
			(layer "B.Fab")
			(effects
				(font
					(size 1.27 1.27)
				)
				(justify mirror)
			)
		)
		(duplicate_pad_numbers_are_jumpers no)
		(fp_line
			(start -0.7874 -0.4064)
			(end -0.7874 0.4064)
			(stroke
				(width 0.1524)
				(type default)
			)
			(layer "B.SilkS")
		)
		(fp_line
			(start -0.7874 0.4064)
			(end 0.7874 0.4064)
			(stroke
				(width 0.1524)
				(type default)
			)
			(layer "B.SilkS")
		)
		(fp_line
			(start 0.7874 -0.4064)
			(end -0.7874 -0.4064)
			(stroke
				(width 0.1524)
				(type default)
			)
			(layer "B.SilkS")
		)
		(fp_line
			(start 0.7874 0.4064)
			(end 0.7874 -0.4064)
			(stroke
				(width 0.1524)
				(type default)
			)
			(layer "B.SilkS")
		)
		(fp_line
			(start -0.67945 -0.3048)
			(end -0.67945 0.3048)
			(stroke
				(width 0.1)
				(type default)
			)
			(layer "B.Fab")
		)
		(fp_line
			(start -0.67945 0.3048)
			(end -0.120396 0.3048)
			(stroke
				(width 0.1)
				(type default)
			)
			(layer "B.Fab")
		)
		(fp_line
			(start -0.12065 -0.3048)
			(end -0.67945 -0.3048)
			(stroke
				(width 0.1)
				(type default)
			)
			(layer "B.Fab")
		)
		(fp_line
			(start -0.12065 -0.2794)
			(end -0.12065 -0.3048)
			(stroke
				(width 0.1)
				(type default)
			)
			(layer "B.Fab")
		)
		(fp_line
			(start -0.120396 0.2794)
			(end 0.12065 0.2794)
			(stroke
				(width 0.1)
				(type default)
			)
			(layer "B.Fab")
		)
		(fp_line
			(start -0.120396 0.3048)
			(end -0.120396 0.2794)
			(stroke
				(width 0.1)
				(type default)
			)
			(layer "B.Fab")
		)
		(fp_line
			(start 0.12065 -0.305054)
			(end 0.12065 -0.2794)
			(stroke
				(width 0.1)
				(type default)
			)
			(layer "B.Fab")
		)
		(fp_line
			(start 0.12065 -0.2794)
			(end -0.12065 -0.2794)
			(stroke
				(width 0.1)
				(type default)
			)
			(layer "B.Fab")
		)
		(fp_line
			(start 0.12065 0.2794)
			(end 0.12065 0.3048)
			(stroke
				(width 0.1)
				(type default)
			)
			(layer "B.Fab")
		)
		(fp_line
			(start 0.12065 0.3048)
			(end 0.67945 0.3048)
			(stroke
				(width 0.1)
				(type default)
			)
			(layer "B.Fab")
		)
		(fp_line
			(start 0.67945 -0.305054)
			(end 0.12065 -0.305054)
			(stroke
				(width 0.1)
				(type default)
			)
			(layer "B.Fab")
		)
		(fp_line
			(start 0.67945 0.3048)
			(end 0.67945 -0.305054)
			(stroke
				(width 0.1)
				(type default)
			)
			(layer "B.Fab")
		)
		(pad "1" smd circle
			(at 0.40005 0 180)
			(size 0 0)
			(layers "B.Cu" "B.Mask" "B.Paste")
			(net "XTAL_CPU0_X48M_X2")
		)
		(pad "2" smd circle
			(at -0.40005 0 180)
			(size 0 0)
			(layers "B.Cu" "B.Mask" "B.Paste")
			(net "XTAL_CPU0_X48M_X2_R")
		)
	)
)
